(kicad_pcb
	(version 20241229)
	(generator "pcbnew")
	(generator_version "9.0")
	(general
		(thickness 1.599998)
		(legacy_teardrops no)
	)
	(paper "A4")
	(title_block
		(date "2023-02-12")
		(rev "1.1.5")
		(comment 9 "footprints 457-462 of 473")
	)
	(layers
		(0 "F.Cu" signal)
		(4 "In1.Cu" power "In1.GND")
		(6 "In2.Cu" signal)
		(8 "In3.Cu" power "In3.GND")
		(10 "In4.Cu" power "In4.VCC")
		(12 "In5.Cu" signal)
		(14 "In6.Cu" power "In6.VCC")
		(2 "B.Cu" signal)
		(9 "F.Adhes" user "F.Adhesive")
		(11 "B.Adhes" user "B.Adhesive")
		(13 "F.Paste" user)
		(15 "B.Paste" user)
		(5 "F.SilkS" user "F.Silkscreen")
		(7 "B.SilkS" user "B.Silkscreen")
		(1 "F.Mask" user)
		(3 "B.Mask" user)
		(17 "Dwgs.User" user "User.Drawings")
		(19 "Cmts.User" user "User.Comments")
		(21 "Eco1.User" user "User.Eco1")
		(23 "Eco2.User" user "User.Eco2")
		(25 "Edge.Cuts" user)
		(27 "Margin" user)
		(31 "F.CrtYd" user "F.Courtyard")
		(29 "B.CrtYd" user "B.Courtyard")
		(35 "F.Fab" user)
		(33 "B.Fab" user)
	)
	(footprint "antmicro-footprints:R_0402_1005Metric"
		(layer "B.Cu")
		(at 134.2 70)
		(descr "Resistor SMD 0402")
		(tags "resistor SMD 0402")
		(property "Reference" "R162"
			(at -0.7 0.4 180)
			(layer "B.SilkS")
			(effects
				(font
					(size 0.7 0.7)
					(thickness 0.15)
				)
				(justify left bottom mirror)
			)
		)
		(property "Value" "R_0R_0402"
			(at 0 -1.4 180)
			(layer "B.Fab")
			(effects
				(font
					(size 0.7 0.7)
					(thickness 0.15)
				)
				(justify left bottom mirror)
			)
		)
		(property "Description" "0R resistor in 0402 package with unspecified tolerance"
			(at 0 0 0)
			(layer "F.Fab")
			(hide yes)
			(effects
				(font
					(size 1.27 1.27)
					(thickness 0.15)
				)
			)
		)
		(property "Author" "Antmicro"
			(at 0 0 0)
			(layer "B.Fab")
			(hide yes)
			(effects
				(font
					(size 1 1)
					(thickness 0.15)
				)
				(justify mirror)
			)
		)
		(property "Current" "1A"
			(at 0 0 0)
			(layer "B.Fab")
			(hide yes)
			(effects
				(font
					(size 1 1)
					(thickness 0.15)
				)
				(justify mirror)
			)
		)
		(property "License" "Apache-2.0"
			(at 0 0 0)
			(layer "B.Fab")
			(hide yes)
			(effects
				(font
					(size 1 1)
					(thickness 0.15)
				)
				(justify mirror)
			)
		)
		(property "MPN" "ERJ2GE0R00X"
			(at 0 0 0)
			(layer "B.Fab")
			(hide yes)
			(effects
				(font
					(size 1 1)
					(thickness 0.15)
				)
				(justify mirror)
			)
		)
		(property "Manufacturer" "Panasonic"
			(at 0 0 0)
			(layer "B.Fab")
			(hide yes)
			(effects
				(font
					(size 1 1)
					(thickness 0.15)
				)
				(justify mirror)
			)
		)
		(property "Tolerance" ""
			(at 0 0 0)
			(layer "B.Fab")
			(hide yes)
			(effects
				(font
					(size 1 1)
					(thickness 0.15)
				)
				(justify mirror)
			)
		)
		(property "Val" "0R"
			(at 0 0 0)
			(layer "B.Fab")
			(hide yes)
			(effects
				(font
					(size 1 1)
					(thickness 0.15)
				)
				(justify mirror)
			)
		)
		(sheetname "Supply")
		(sheetfile "supply.kicad_sch")
		(attr exclude_from_pos_files exclude_from_bom dnp)
		(fp_rect
			(start -0.93 0.47)
			(end 0.93 -0.47)
			(stroke
				(width 0.05)
				(type solid)
			)
			(fill no)
			(layer "B.CrtYd")
		)
		(fp_rect
			(start -0.5 0.25)
			(end 0.5 -0.25)
			(stroke
				(width 0.15)
				(type solid)
			)
			(fill no)
			(layer "B.Fab")
		)
		(pad "1" smd roundrect
			(at -0.485 0)
			(size 0.59 0.64)
			(layers "B.Cu" "B.Mask" "B.Paste")
			(roundrect_rratio 0.25)
			(net 646 "FPGA_AA21_BALL")
			(pintype "passive")
		)
		(pad "2" smd roundrect
			(at 0.485 0)
			(size 0.59 0.64)
			(layers "B.Cu" "B.Mask" "B.Paste")
			(roundrect_rratio 0.25)
			(net 264 "Net-(U16-ON)")
			(pintype "passive")
		)
	)
	(footprint "antmicro-footprints:R_0402_1005Metric"
		(layer "B.Cu")
		(at 196.216328 98.210008)
		(descr "Resistor SMD 0402")
		(tags "resistor SMD 0402")
		(property "Reference" "R90"
			(at -3.926328 2.399992 0)
			(layer "B.SilkS")
			(effects
				(font
					(size 0.7 0.7)
					(thickness 0.15)
				)
				(justify right bottom mirror)
			)
		)
		(property "Value" "R_2k2_0402"
			(at 0 -1.4 0)
			(layer "B.Fab")
			(effects
				(font
					(size 0.7 0.7)
					(thickness 0.15)
				)
				(justify right bottom mirror)
			)
		)
		(property "Description" "2k2 resistor in 0402 package with 1% tolerance"
			(at 0 0 0)
			(layer "F.Fab")
			(hide yes)
			(effects
				(font
					(size 1.27 1.27)
					(thickness 0.15)
				)
			)
		)
		(property "Author" "Antmicro"
			(at 0 0 0)
			(layer "B.Fab")
			(hide yes)
			(effects
				(font
					(size 1 1)
					(thickness 0.15)
				)
				(justify mirror)
			)
		)
		(property "License" "Apache-2.0"
			(at 0 0 0)
			(layer "B.Fab")
			(hide yes)
			(effects
				(font
					(size 1 1)
					(thickness 0.15)
				)
				(justify mirror)
			)
		)
		(property "MPN" "CR0402-FX-2201GLF"
			(at 0 0 0)
			(layer "B.Fab")
			(hide yes)
			(effects
				(font
					(size 1 1)
					(thickness 0.15)
				)
				(justify mirror)
			)
		)
		(property "Manufacturer" "Bourns"
			(at 0 0 0)
			(layer "B.Fab")
			(hide yes)
			(effects
				(font
					(size 1 1)
					(thickness 0.15)
				)
				(justify mirror)
			)
		)
		(property "Tolerance" "1%"
			(at 0 0 0)
			(layer "B.Fab")
			(hide yes)
			(effects
				(font
					(size 1 1)
					(thickness 0.15)
				)
				(justify mirror)
			)
		)
		(property "Val" "2k2"
			(at 0 0 0)
			(layer "B.Fab")
			(hide yes)
			(effects
				(font
					(size 1 1)
					(thickness 0.15)
				)
				(justify mirror)
			)
		)
		(sheetname "Ethernet")
		(sheetfile "ethernet.kicad_sch")
		(attr smd)
		(fp_rect
			(start -0.93 0.47)
			(end 0.93 -0.47)
			(stroke
				(width 0.05)
				(type solid)
			)
			(fill no)
			(layer "B.CrtYd")
		)
		(fp_rect
			(start -0.5 0.25)
			(end 0.5 -0.25)
			(stroke
				(width 0.15)
				(type solid)
			)
			(fill no)
			(layer "B.Fab")
		)
		(pad "1" smd roundrect
			(at -0.485 0)
			(size 0.59 0.64)
			(layers "B.Cu" "B.Mask" "B.Paste")
			(roundrect_rratio 0.25)
			(net 36 "ETH_RX_CLK")
			(pintype "passive")
		)
		(pad "2" smd roundrect
			(at 0.485 0)
			(size 0.59 0.64)
			(layers "B.Cu" "B.Mask" "B.Paste")
			(roundrect_rratio 0.25)
			(net 5 "GND")
			(pintype "passive")
		)
	)
	(footprint "antmicro-footprints:R_0402_1005Metric"
		(layer "B.Cu")
		(at 122.7 68.95 180)
		(descr "Resistor SMD 0402")
		(tags "resistor SMD 0402")
		(property "Reference" "R159"
			(at -1.4 -1.25 0)
			(layer "B.SilkS")
			(effects
				(font
					(size 0.7 0.7)
					(thickness 0.15)
				)
				(justify left bottom mirror)
			)
		)
		(property "Value" "R_10k_0402"
			(at 0 -1.4 0)
			(layer "B.Fab")
			(effects
				(font
					(size 0.7 0.7)
					(thickness 0.15)
				)
				(justify left bottom mirror)
			)
		)
		(property "Description" "10k resistor in 0402 package with 1% tolerance"
			(at 0 0 180)
			(layer "F.Fab")
			(hide yes)
			(effects
				(font
					(size 1.27 1.27)
					(thickness 0.15)
				)
			)
		)
		(property "Author" "Antmicro"
			(at 245.4 137.9 0)
			(layer "B.Fab")
			(hide yes)
			(effects
				(font
					(size 1 1)
					(thickness 0.15)
				)
				(justify mirror)
			)
		)
		(property "License" "Apache-2.0"
			(at 245.4 137.9 0)
			(layer "B.Fab")
			(hide yes)
			(effects
				(font
					(size 1 1)
					(thickness 0.15)
				)
				(justify mirror)
			)
		)
		(property "MPN" "CR0402-FX-1002GLF"
			(at 245.4 137.9 0)
			(layer "B.Fab")
			(hide yes)
			(effects
				(font
					(size 1 1)
					(thickness 0.15)
				)
				(justify mirror)
			)
		)
		(property "Manufacturer" "Bourns"
			(at 245.4 137.9 0)
			(layer "B.Fab")
			(hide yes)
			(effects
				(font
					(size 1 1)
					(thickness 0.15)
				)
				(justify mirror)
			)
		)
		(property "Tolerance" "1%"
			(at 245.4 137.9 0)
			(layer "B.Fab")
			(hide yes)
			(effects
				(font
					(size 1 1)
					(thickness 0.15)
				)
				(justify mirror)
			)
		)
		(property "Val" "10k"
			(at 245.4 137.9 0)
			(layer "B.Fab")
			(hide yes)
			(effects
				(font
					(size 1 1)
					(thickness 0.15)
				)
				(justify mirror)
			)
		)
		(sheetname "Supply")
		(sheetfile "supply.kicad_sch")
		(attr exclude_from_pos_files exclude_from_bom dnp)
		(fp_rect
			(start -0.93 0.47)
			(end 0.93 -0.47)
			(stroke
				(width 0.05)
				(type solid)
			)
			(fill no)
			(layer "B.CrtYd")
		)
		(fp_rect
			(start -0.5 0.25)
			(end 0.5 -0.25)
			(stroke
				(width 0.15)
				(type solid)
			)
			(fill no)
			(layer "B.Fab")
		)
		(pad "1" smd roundrect
			(at -0.485 0 180)
			(size 0.59 0.64)
			(layers "B.Cu" "B.Mask" "B.Paste")
			(roundrect_rratio 0.25)
			(net 238 "Net-(Q13-G)")
			(pintype "passive")
		)
		(pad "2" smd roundrect
			(at 0.485 0 180)
			(size 0.59 0.64)
			(layers "B.Cu" "B.Mask" "B.Paste")
			(roundrect_rratio 0.25)
			(net 5 "GND")
			(pintype "passive")
		)
	)
	(footprint "antmicro-footprints:R_0402_1005Metric"
		(layer "B.Cu")
		(at 134.2 78.4)
		(descr "Resistor SMD 0402")
		(tags "resistor SMD 0402")
		(property "Reference" "R160"
			(at -0.7 0.4 180)
			(layer "B.SilkS")
			(effects
				(font
					(size 0.7 0.7)
					(thickness 0.15)
				)
				(justify left bottom mirror)
			)
		)
		(property "Value" "R_0R_0402"
			(at 0 -1.4 180)
			(layer "B.Fab")
			(effects
				(font
					(size 0.7 0.7)
					(thickness 0.15)
				)
				(justify left bottom mirror)
			)
		)
		(property "Description" "0R resistor in 0402 package with unspecified tolerance"
			(at 0 0 0)
			(layer "F.Fab")
			(hide yes)
			(effects
				(font
					(size 1.27 1.27)
					(thickness 0.15)
				)
			)
		)
		(property "Author" "Antmicro"
			(at 0 0 0)
			(layer "B.Fab")
			(hide yes)
			(effects
				(font
					(size 1 1)
					(thickness 0.15)
				)
				(justify mirror)
			)
		)
		(property "Current" "1A"
			(at 0 0 0)
			(layer "B.Fab")
			(hide yes)
			(effects
				(font
					(size 1 1)
					(thickness 0.15)
				)
				(justify mirror)
			)
		)
		(property "License" "Apache-2.0"
			(at 0 0 0)
			(layer "B.Fab")
			(hide yes)
			(effects
				(font
					(size 1 1)
					(thickness 0.15)
				)
				(justify mirror)
			)
		)
		(property "MPN" "ERJ2GE0R00X"
			(at 0 0 0)
			(layer "B.Fab")
			(hide yes)
			(effects
				(font
					(size 1 1)
					(thickness 0.15)
				)
				(justify mirror)
			)
		)
		(property "Manufacturer" "Panasonic"
			(at 0 0 0)
			(layer "B.Fab")
			(hide yes)
			(effects
				(font
					(size 1 1)
					(thickness 0.15)
				)
				(justify mirror)
			)
		)
		(property "Tolerance" ""
			(at 0 0 0)
			(layer "B.Fab")
			(hide yes)
			(effects
				(font
					(size 1 1)
					(thickness 0.15)
				)
				(justify mirror)
			)
		)
		(property "Val" "0R"
			(at 0 0 0)
			(layer "B.Fab")
			(hide yes)
			(effects
				(font
					(size 1 1)
					(thickness 0.15)
				)
				(justify mirror)
			)
		)
		(sheetname "Supply")
		(sheetfile "supply.kicad_sch")
		(attr exclude_from_pos_files exclude_from_bom dnp)
		(fp_rect
			(start -0.93 0.47)
			(end 0.93 -0.47)
			(stroke
				(width 0.05)
				(type solid)
			)
			(fill no)
			(layer "B.CrtYd")
		)
		(fp_rect
			(start -0.5 0.25)
			(end 0.5 -0.25)
			(stroke
				(width 0.15)
				(type solid)
			)
			(fill no)
			(layer "B.Fab")
		)
		(pad "1" smd roundrect
			(at -0.485 0)
			(size 0.59 0.64)
			(layers "B.Cu" "B.Mask" "B.Paste")
			(roundrect_rratio 0.25)
			(net 644 "FPGA_AB21_BALL")
			(pintype "passive")
		)
		(pad "2" smd roundrect
			(at 0.485 0)
			(size 0.59 0.64)
			(layers "B.Cu" "B.Mask" "B.Paste")
			(roundrect_rratio 0.25)
			(net 263 "Net-(U15-ON)")
			(pintype "passive")
		)
	)
	(footprint "antmicro-footprints:RENESAS-TDFN-8-1.5x2.0mm_P0.5mm"
		(layer "B.Cu")
		(at 136.3 69.5)
		(descr "8 Lead TDFN Package 1.5 x 2.0 mm (Fused Lead) JEDEC MO-252 ")
		(property "Reference" "U16"
			(at -3.458 -1.174 180)
			(unlocked yes)
			(layer "B.SilkS")
			(effects
				(font
					(size 0.7 0.7)
					(thickness 0.15)
				)
				(justify left bottom mirror)
			)
		)
		(property "Value" "SLG59M1457V"
			(at -9.7 -2.4 180)
			(unlocked yes)
			(layer "B.Fab")
			(effects
				(font
					(size 0.7 0.7)
					(thickness 0.15)
				)
				(justify left bottom mirror)
			)
		)
		(property "Description" "Power distribution switch/load driver"
			(at 0 0 0)
			(layer "F.Fab")
			(hide yes)
			(effects
				(font
					(size 1.27 1.27)
					(thickness 0.15)
				)
			)
		)
		(property "Author" "Antmicro"
			(at 0 0 0)
			(layer "B.Fab")
			(hide yes)
			(effects
				(font
					(size 1 1)
					(thickness 0.15)
				)
				(justify mirror)
			)
		)
		(property "License" "Apache-2.0"
			(at 0 0 0)
			(layer "B.Fab")
			(hide yes)
			(effects
				(font
					(size 1 1)
					(thickness 0.15)
				)
				(justify mirror)
			)
		)
		(property "MPN" "SLG59M1457V"
			(at 0 0 0)
			(layer "B.Fab")
			(hide yes)
			(effects
				(font
					(size 1 1)
					(thickness 0.15)
				)
				(justify mirror)
			)
		)
		(property "Manufacturer" "Dialog Semiconductor"
			(at 0 0 0)
			(layer "B.Fab")
			(hide yes)
			(effects
				(font
					(size 1 1)
					(thickness 0.15)
				)
				(justify mirror)
			)
		)
		(sheetname "Supply")
		(sheetfile "supply.kicad_sch")
		(attr exclude_from_pos_files exclude_from_bom dnp)
		(fp_line
			(start -0.946 1.101)
			(end 0.498 1.101)
			(stroke
				(width 0.15)
				(type solid)
			)
			(layer "B.SilkS")
		)
		(fp_line
			(start -0.5 -1.1)
			(end 0.498 -1.1)
			(stroke
				(width 0.15)
				(type solid)
			)
			(layer "B.SilkS")
		)
		(fp_circle
			(center -1.3 0.75)
			(end -1.249 0.75)
			(stroke
				(width 0.15)
				(type solid)
			)
			(fill yes)
			(layer "B.SilkS")
		)
		(fp_rect
			(start -1.25 1.5)
			(end 1.248 -1.498)
			(stroke
				(width 0.05)
				(type solid)
			)
			(fill no)
			(layer "B.CrtYd")
		)
		(fp_line
			(start -0.777 -1.03)
			(end 0.785 -1.03)
			(stroke
				(width 0.15)
				(type solid)
			)
			(layer "B.Fab")
		)
		(fp_line
			(start -0.777 0.75)
			(end -0.777 -1.03)
			(stroke
				(width 0.15)
				(type solid)
			)
			(layer "B.Fab")
		)
		(fp_line
			(start -0.495 1.031)
			(end -0.777 0.75)
			(stroke
				(width 0.15)
				(type solid)
			)
			(layer "B.Fab")
		)
		(fp_line
			(start 0.785 1.031)
			(end -0.495 1.031)
			(stroke
				(width 0.15)
				(type solid)
			)
			(layer "B.Fab")
		)
		(fp_line
			(start 0.785 1.031)
			(end 0.785 -1.03)
			(stroke
				(width 0.15)
				(type solid)
			)
			(layer "B.Fab")
		)
		(pad "1" smd rect
			(at -0.527 0.75 90)
			(size 0.28 0.85)
			(layers "B.Cu" "B.Mask" "B.Paste")
			(net 459 "3V3_SYS")
			(pinfunction "VDD")
			(pintype "power_in")
		)
		(pad "2" smd rect
			(at -0.576 0.25 90)
			(size 0.28 0.75)
			(layers "B.Cu" "B.Mask" "B.Paste")
			(net 264 "Net-(U16-ON)")
			(pinfunction "ON")
			(pintype "input")
		)
		(pad "3" smd custom
			(at -0.576 -0.248 90)
			(size 0.28 0.75)
			(layers "B.Cu" "B.Mask" "B.Paste")
			(net 460 "1V8_SYS")
			(pinfunction "IN")
			(pintype "power_in")
			(zone_connect 2)
			(options
				(clearance outline)
				(anchor rect)
			)
			(primitives
				(gr_poly
					(pts
						(xy -0.14 0.375) (xy -0.14 -0.05) (xy 0.64 -0.05) (xy 0.64 0.375)
					)
					(width 0)
					(fill yes)
				)
				(gr_rect
					(start 0.36 -0.375)
					(end 0.64 0.375)
					(width 0)
					(fill yes)
				)
			)
		)
		(pad "5" smd custom
			(at 0.574 -0.748 270)
			(size 0.28 0.75)
			(layers "B.Cu" "B.Mask" "B.Paste")
			(net 641 "1V8_DDR")
			(pinfunction "OUT")
			(pintype "power_out")
			(zone_connect 2)
			(options
				(clearance outline)
				(anchor rect)
			)
			(primitives
				(gr_poly
					(pts
						(xy -0.14 0.375) (xy -0.14 -0.05) (xy 0.64 -0.05) (xy 0.64 0.375)
					)
					(width 0)
					(fill yes)
				)
				(gr_rect
					(start 0.36 -0.375)
					(end 0.64 0.375)
					(width 0)
					(fill yes)
				)
			)
		)
		(pad "7" smd rect
			(at 0.574 0.25 90)
			(size 0.28 0.75)
			(layers "B.Cu" "B.Mask" "B.Paste")
			(net 62 "Net-(U16-CAP)")
			(pinfunction "CAP")
			(pintype "input")
		)
		(pad "8" smd rect
			(at 0.574 0.75 90)
			(size 0.28 0.75)
			(layers "B.Cu" "B.Mask" "B.Paste")
			(net 5 "GND")
			(pinfunction "GND")
			(pintype "passive")
		)
	)
	(footprint "antmicro-footprints:R_0402_1005Metric"
		(layer "B.Cu")
		(at 121 59.4)
		(descr "Resistor SMD 0402")
		(tags "resistor SMD 0402")
		(property "Reference" "R116"
			(at 1.4 1.3 180)
			(layer "B.SilkS")
			(effects
				(font
					(size 0.7 0.7)
					(thickness 0.15)
				)
				(justify left bottom mirror)
			)
		)
		(property "Value" "R_100k_0402"
			(at 0 -1.4 180)
			(layer "B.Fab")
			(effects
				(font
					(size 0.7 0.7)
					(thickness 0.15)
				)
				(justify left bottom mirror)
			)
		)
		(property "Description" "100k resistor in 0402 package with 1% tolerance"
			(at 0 0 0)
			(layer "F.Fab")
			(hide yes)
			(effects
				(font
					(size 1.27 1.27)
					(thickness 0.15)
				)
			)
		)
		(property "Author" "Antmicro"
			(at 0 0 0)
			(layer "B.Fab")
			(hide yes)
			(effects
				(font
					(size 1 1)
					(thickness 0.15)
				)
				(justify mirror)
			)
		)
		(property "License" "Apache-2.0"
			(at 0 0 0)
			(layer "B.Fab")
			(hide yes)
			(effects
				(font
					(size 1 1)
					(thickness 0.15)
				)
				(justify mirror)
			)
		)
		(property "MPN" "CR0402-FX-1003GLF"
			(at 0 0 0)
			(layer "B.Fab")
			(hide yes)
			(effects
				(font
					(size 1 1)
					(thickness 0.15)
				)
				(justify mirror)
			)
		)
		(property "Manufacturer" "Bourns"
			(at 0 0 0)
			(layer "B.Fab")
			(hide yes)
			(effects
				(font
					(size 1 1)
					(thickness 0.15)
				)
				(justify mirror)
			)
		)
		(property "Tolerance" "1%"
			(at 0 0 0)
			(layer "B.Fab")
			(hide yes)
			(effects
				(font
					(size 1 1)
					(thickness 0.15)
				)
				(justify mirror)
			)
		)
		(property "Val" "100k"
			(at 0 0 0)
			(layer "B.Fab")
			(hide yes)
			(effects
				(font
					(size 1 1)
					(thickness 0.15)
				)
				(justify mirror)
			)
		)
		(sheetname "Supply")
		(sheetfile "supply.kicad_sch")
		(attr exclude_from_pos_files exclude_from_bom dnp)
		(fp_rect
			(start -0.93 0.47)
			(end 0.93 -0.47)
			(stroke
				(width 0.05)
				(type solid)
			)
			(fill no)
			(layer "B.CrtYd")
		)
		(fp_rect
			(start -0.5 0.25)
			(end 0.5 -0.25)
			(stroke
				(width 0.15)
				(type solid)
			)
			(fill no)
			(layer "B.Fab")
		)
		(pad "1" smd roundrect
			(at -0.485 0)
			(size 0.59 0.64)
			(layers "B.Cu" "B.Mask" "B.Paste")
			(roundrect_rratio 0.25)
			(net 463 "VCC5V0_INT")
			(pintype "passive")
		)
		(pad "2" smd roundrect
			(at 0.485 0)
			(size 0.59 0.64)
			(layers "B.Cu" "B.Mask" "B.Paste")
			(roundrect_rratio 0.25)
			(net 630 "/Supply/LPDDR4_PGOOD")
			(pintype "passive")
		)
	)
)
